(kicad_pcb
	(version 20260206)
	(generator "pcbnew")
	(generator_version "10.0")
	(general
		(thickness 1.6)
		(legacy_teardrops no)
	)
	(paper "A4")
	(title_block
		(title "netronome-mezz — pcbd0082-001_rev01_jul9_a.brd")
		(comment 1 "Open CloudServer (Microsoft) / footprint 225 of 714 (U1), pads 581-695 of 1022")
	)
	(layers
		(0 "F.Cu" signal "TOP")
		(4 "In1.Cu" signal "02_GND")
		(6 "In2.Cu" signal "03_SIG")
		(8 "In3.Cu" signal "04_SIG")
		(10 "In4.Cu" signal "05_GND")
		(12 "In5.Cu" signal "06_PWR1")
		(14 "In6.Cu" signal "07_SIG")
		(16 "In7.Cu" signal "08_SIG")
		(18 "In8.Cu" signal "09_GND")
		(2 "B.Cu" signal "BOTTOM")
		(9 "F.Adhes" user "F.Adhesive")
		(11 "B.Adhes" user "B.Adhesive")
		(13 "F.Paste" user "Package Geometry/Pastemask Top")
		(15 "B.Paste" user "Package Geometry/Pastemask Bottom")
		(5 "F.SilkS" user "Ref Des/Silkscreen Top")
		(7 "B.SilkS" user "Ref Des/Silkscreen Bottom")
		(1 "F.Mask" user "Board Geometry/Soldermask Top")
		(3 "B.Mask" user "Board Geometry/Soldermask Bottom")
		(17 "Dwgs.User" user "User.Drawings")
		(19 "Cmts.User" user "User.Comments")
		(21 "Eco1.User" user "User.Eco1")
		(23 "Eco2.User" user "User.Eco2")
		(25 "Edge.Cuts" user "Board Geometry/Outline")
		(27 "Margin" user)
		(31 "F.CrtYd" user "Package Geometry/Place Bound Top")
		(29 "B.CrtYd" user "Package Geometry/Place Bound Bottom")
		(35 "F.Fab" user "Ref Des/Assembly Top")
		(33 "B.Fab" user "Ref Des/Assembly Bottom")
		(45 "User.4" user "COMPVAL_TYPE_BOTTOM")
	)
	(footprint ""
		(layer "F.Cu")
		(at 54.737 18.542 180)
		(property "Reference" "U1"
			(at -12.192 17.9705 0)
			(unlocked yes)
			(layer "F.SilkS")
			(effects
				(font
					(size 1.27 0.9652)
					(thickness 0.1524)
				)
				(justify left)
			)
		)
		(property "Value" "*"
			(at -0.4826 1.74879 180)
			(unlocked yes)
			(layer "F.Fab")
			(hide yes)
			(effects
				(font
					(size 1.27 0.9652)
					(thickness 0.000001)
				)
				(justify left)
			)
		)
		(property "Device Type" "ICBG0048"
			(at -0.4826 1.74879 180)
			(unlocked yes)
			(layer "F.Fab")
			(hide yes)
			(effects
				(font
					(size 1.27 0.9652)
					(thickness 0.000001)
				)
				(justify left)
			)
		)
		(duplicate_pad_numbers_are_jumpers no)
		(pad "G7" smd circle
			(at -9.500006 -9.500006 180)
			(size 0.508 0.508)
			(layers "F.Cu" "F.Mask" "F.Paste")
			(net "_NC_DDR0_32B_CK1_N")
		)
		(pad "G8" smd circle
			(at -8.500008 -9.500006 180)
			(size 0.508 0.508)
			(layers "F.Cu" "F.Mask" "F.Paste")
			(net "_NC_DDR0_32B_A2")
		)
		(pad "G9" smd circle
			(at -7.50001 -9.500006 180)
			(size 0.508 0.508)
			(layers "F.Cu" "F.Mask" "F.Paste")
			(net "_NC_DDR0_32B_A0")
		)
		(pad "G10" smd circle
			(at -6.500012 -9.500006 180)
			(size 0.508 0.508)
			(layers "F.Cu" "F.Mask" "F.Paste")
			(net "GND")
		)
		(pad "G11" smd circle
			(at -5.499989 -9.500006 180)
			(size 0.508 0.508)
			(layers "F.Cu" "F.Mask" "F.Paste")
			(net "VDD_CORE")
		)
		(pad "G12" smd circle
			(at -4.499991 -9.500006 180)
			(size 0.508 0.508)
			(layers "F.Cu" "F.Mask" "F.Paste")
			(net "GND")
		)
		(pad "G13" smd circle
			(at -3.499993 -9.500006 180)
			(size 0.508 0.508)
			(layers "F.Cu" "F.Mask" "F.Paste")
			(net "VDD_CORE")
		)
		(pad "G14" smd circle
			(at -2.499995 -9.500006 180)
			(size 0.508 0.508)
			(layers "F.Cu" "F.Mask" "F.Paste")
			(net "GND")
		)
		(pad "G15" smd circle
			(at -1.499997 -9.500006 180)
			(size 0.508 0.508)
			(layers "F.Cu" "F.Mask" "F.Paste")
			(net "VDD_CORE")
		)
		(pad "G16" smd circle
			(at -0.499999 -9.500006 180)
			(size 0.508 0.508)
			(layers "F.Cu" "F.Mask" "F.Paste")
			(net "GND")
		)
		(pad "G17" smd circle
			(at 0.499999 -9.500006 180)
			(size 0.508 0.508)
			(layers "F.Cu" "F.Mask" "F.Paste")
			(net "VDD_CORE")
		)
		(pad "G18" smd circle
			(at 1.499997 -9.500006 180)
			(size 0.508 0.508)
			(layers "F.Cu" "F.Mask" "F.Paste")
			(net "GND")
		)
		(pad "G19" smd circle
			(at 2.499995 -9.500006 180)
			(size 0.508 0.508)
			(layers "F.Cu" "F.Mask" "F.Paste")
			(net "VDD_CORE")
		)
		(pad "G20" smd circle
			(at 3.499993 -9.500006 180)
			(size 0.508 0.508)
			(layers "F.Cu" "F.Mask" "F.Paste")
			(net "GND")
		)
		(pad "G21" smd circle
			(at 4.499991 -9.500006 180)
			(size 0.508 0.508)
			(layers "F.Cu" "F.Mask" "F.Paste")
			(net "VDD_CORE")
		)
		(pad "G22" smd circle
			(at 5.499989 -9.500006 180)
			(size 0.508 0.508)
			(layers "F.Cu" "F.Mask" "F.Paste")
			(net "GND")
		)
		(pad "G23" smd circle
			(at 6.500012 -9.500006 180)
			(size 0.508 0.508)
			(layers "F.Cu" "F.Mask" "F.Paste")
			(net "VDD_CORE")
		)
		(pad "G24" smd circle
			(at 7.50001 -9.500006 180)
			(size 0.508 0.508)
			(layers "F.Cu" "F.Mask" "F.Paste")
			(net "GND")
		)
		(pad "G25" smd circle
			(at 8.500008 -9.500006 180)
			(size 0.508 0.508)
			(layers "F.Cu" "F.Mask" "F.Paste")
			(net "VDD_CORE")
		)
		(pad "G26" smd circle
			(at 9.500006 -9.500006 180)
			(size 0.508 0.508)
			(layers "F.Cu" "F.Mask" "F.Paste")
			(net "GND")
		)
		(pad "G27" smd circle
			(at 10.500004 -9.500006 180)
			(size 0.508 0.508)
			(layers "F.Cu" "F.Mask" "F.Paste")
			(net "VDD_CORE")
		)
		(pad "G28" smd circle
			(at 11.500002 -9.500006 180)
			(size 0.508 0.508)
			(layers "F.Cu" "F.Mask" "F.Paste")
			(net "_NC_TEST_SCAN_0_OUT12")
		)
		(pad "G29" smd circle
			(at 12.5 -9.500006 180)
			(size 0.508 0.508)
			(layers "F.Cu" "F.Mask" "F.Paste")
			(net "_NC_TEST_SCAN_0_OUT11")
		)
		(pad "G30" smd circle
			(at 13.499998 -9.500006 180)
			(size 0.508 0.508)
			(layers "F.Cu" "F.Mask" "F.Paste")
			(net "_NC_TEST_SCAN_0_OUT17")
		)
		(pad "G31" smd circle
			(at 14.499996 -9.500006 180)
			(size 0.508 0.508)
			(layers "F.Cu" "F.Mask" "F.Paste")
			(net "_NC_VDDQ_TEST_SCAN_0_OUT_2")
		)
		(pad "G32" smd circle
			(at 15.499994 -9.500006 180)
			(size 0.508 0.508)
			(layers "F.Cu" "F.Mask" "F.Paste")
			(net "_NC_TEST_SCAN_0_OUT10")
		)
		(pad "H1" smd circle
			(at -15.499994 -8.500008 180)
			(size 0.508 0.508)
			(layers "F.Cu" "F.Mask" "F.Paste")
			(net "_NC_DDR0_32B_DQ17")
		)
		(pad "H2" smd circle
			(at -14.499996 -8.500008 180)
			(size 0.508 0.508)
			(layers "F.Cu" "F.Mask" "F.Paste")
			(net "_NC_DDR0_32B_DM2")
		)
		(pad "H3" smd circle
			(at -13.499998 -8.500008 180)
			(size 0.508 0.508)
			(layers "F.Cu" "F.Mask" "F.Paste")
			(net "_NC_DDR0_32B_DQ23")
		)
		(pad "H4" smd circle
			(at -12.5 -8.500008 180)
			(size 0.508 0.508)
			(layers "F.Cu" "F.Mask" "F.Paste")
			(net "_NC_DDR0_32B_DQ19")
		)
		(pad "H5" smd circle
			(at -11.500002 -8.500008 180)
			(size 0.508 0.508)
			(layers "F.Cu" "F.Mask" "F.Paste")
			(net "_NC_DDR0_32B_DQ16")
		)
		(pad "H6" smd circle
			(at -10.500004 -8.500008 180)
			(size 0.508 0.508)
			(layers "F.Cu" "F.Mask" "F.Paste")
			(net "_NC_DDR0_32B_CK1_P")
		)
		(pad "H7" smd circle
			(at -9.500006 -8.500008 180)
			(size 0.508 0.508)
			(layers "F.Cu" "F.Mask" "F.Paste")
			(net "_NC_DDR0_32B_BA2")
		)
		(pad "H8" smd circle
			(at -8.500008 -8.500008 180)
			(size 0.508 0.508)
			(layers "F.Cu" "F.Mask" "F.Paste")
			(net "_NC_B_DZQ0")
		)
		(pad "H9" smd circle
			(at -7.50001 -8.500008 180)
			(size 0.508 0.508)
			(layers "F.Cu" "F.Mask" "F.Paste")
			(net "_NC_DDR0_32B_CKE1")
		)
		(pad "H10" smd circle
			(at -6.500012 -8.500008 180)
			(size 0.508 0.508)
			(layers "F.Cu" "F.Mask" "F.Paste")
			(net "DDR_VDDQ")
		)
		(pad "H11" smd circle
			(at -5.499989 -8.500008 180)
			(size 0.508 0.508)
			(layers "F.Cu" "F.Mask" "F.Paste")
			(net "GND")
		)
		(pad "H12" smd circle
			(at -4.499991 -8.500008 180)
			(size 0.508 0.508)
			(layers "F.Cu" "F.Mask" "F.Paste")
			(net "VDD_CORE")
		)
		(pad "H13" smd circle
			(at -3.499993 -8.500008 180)
			(size 0.508 0.508)
			(layers "F.Cu" "F.Mask" "F.Paste")
			(net "GND")
		)
		(pad "H14" smd circle
			(at -2.499995 -8.500008 180)
			(size 0.508 0.508)
			(layers "F.Cu" "F.Mask" "F.Paste")
			(net "VDD_CORE")
		)
		(pad "H15" smd circle
			(at -1.499997 -8.500008 180)
			(size 0.508 0.508)
			(layers "F.Cu" "F.Mask" "F.Paste")
			(net "GND")
		)
		(pad "H16" smd circle
			(at -0.499999 -8.500008 180)
			(size 0.508 0.508)
			(layers "F.Cu" "F.Mask" "F.Paste")
			(net "VDD_CORE")
		)
		(pad "H17" smd circle
			(at 0.499999 -8.500008 180)
			(size 0.508 0.508)
			(layers "F.Cu" "F.Mask" "F.Paste")
			(net "GND")
		)
		(pad "H18" smd circle
			(at 1.499997 -8.500008 180)
			(size 0.508 0.508)
			(layers "F.Cu" "F.Mask" "F.Paste")
			(net "VDD_CORE")
		)
		(pad "H19" smd circle
			(at 2.499995 -8.500008 180)
			(size 0.508 0.508)
			(layers "F.Cu" "F.Mask" "F.Paste")
			(net "GND")
		)
		(pad "H20" smd circle
			(at 3.499993 -8.500008 180)
			(size 0.508 0.508)
			(layers "F.Cu" "F.Mask" "F.Paste")
			(net "VDD_CORE")
		)
		(pad "H21" smd circle
			(at 4.499991 -8.500008 180)
			(size 0.508 0.508)
			(layers "F.Cu" "F.Mask" "F.Paste")
			(net "GND")
		)
		(pad "H22" smd circle
			(at 5.499989 -8.500008 180)
			(size 0.508 0.508)
			(layers "F.Cu" "F.Mask" "F.Paste")
			(net "VDD_CORE")
		)
		(pad "H23" smd circle
			(at 6.500012 -8.500008 180)
			(size 0.508 0.508)
			(layers "F.Cu" "F.Mask" "F.Paste")
			(net "GND")
		)
		(pad "H24" smd circle
			(at 7.50001 -8.500008 180)
			(size 0.508 0.508)
			(layers "F.Cu" "F.Mask" "F.Paste")
			(net "VDD_CORE")
		)
		(pad "H25" smd circle
			(at 8.500008 -8.500008 180)
			(size 0.508 0.508)
			(layers "F.Cu" "F.Mask" "F.Paste")
			(net "GND")
		)
		(pad "H26" smd circle
			(at 9.500006 -8.500008 180)
			(size 0.508 0.508)
			(layers "F.Cu" "F.Mask" "F.Paste")
			(net "VDD_CORE")
		)
		(pad "H27" smd circle
			(at 10.500004 -8.500008 180)
			(size 0.508 0.508)
			(layers "F.Cu" "F.Mask" "F.Paste")
			(net "GND")
		)
		(pad "H28" smd circle
			(at 11.500002 -8.500008 180)
			(size 0.508 0.508)
			(layers "F.Cu" "F.Mask" "F.Paste")
			(net "_NC_TEST_SCAN_0_OUT7")
		)
		(pad "H29" smd circle
			(at 12.5 -8.500008 180)
			(size 0.508 0.508)
			(layers "F.Cu" "F.Mask" "F.Paste")
			(net "_NC_TEST_SCAN_0_OUT6")
		)
		(pad "H30" smd circle
			(at 13.499998 -8.500008 180)
			(size 0.508 0.508)
			(layers "F.Cu" "F.Mask" "F.Paste")
			(net "_NC_TEST_SCAN_0_OUT8")
		)
		(pad "H31" smd circle
			(at 14.499996 -8.500008 180)
			(size 0.508 0.508)
			(layers "F.Cu" "F.Mask" "F.Paste")
			(net "_NC_TEST_SCAN_0_OUT5")
		)
		(pad "H32" smd circle
			(at 15.499994 -8.500008 180)
			(size 0.508 0.508)
			(layers "F.Cu" "F.Mask" "F.Paste")
			(net "_NC_TEST_SCAN_0_OUT9")
		)
		(pad "J1" smd circle
			(at -15.499994 -7.50001 180)
			(size 0.508 0.508)
			(layers "F.Cu" "F.Mask" "F.Paste")
			(net "_NC_DDR0_32B_DQS2_P")
		)
		(pad "J2" smd circle
			(at -14.499996 -7.50001 180)
			(size 0.508 0.508)
			(layers "F.Cu" "F.Mask" "F.Paste")
			(net "_NC_DDR0_32B_DQS2_N")
		)
		(pad "J3" smd circle
			(at -13.499998 -7.50001 180)
			(size 0.508 0.508)
			(layers "F.Cu" "F.Mask" "F.Paste")
			(net "DDR_VDDQ")
		)
		(pad "J4" smd circle
			(at -12.5 -7.50001 180)
			(size 0.508 0.508)
			(layers "F.Cu" "F.Mask" "F.Paste")
			(net "_NC_DDR0_32B_DQ22")
		)
		(pad "J5" smd circle
			(at -11.500002 -7.50001 180)
			(size 0.508 0.508)
			(layers "F.Cu" "F.Mask" "F.Paste")
			(net "_NC_DDR0_32B_DQ18")
		)
		(pad "J6" smd circle
			(at -10.500004 -7.50001 180)
			(size 0.508 0.508)
			(layers "F.Cu" "F.Mask" "F.Paste")
			(net "DDR_VDDQ")
		)
		(pad "J7" smd circle
			(at -9.500006 -7.50001 180)
			(size 0.508 0.508)
			(layers "F.Cu" "F.Mask" "F.Paste")
			(net "_NC_DDR0_32B_A4")
		)
		(pad "J8" smd circle
			(at -8.500008 -7.50001 180)
			(size 0.508 0.508)
			(layers "F.Cu" "F.Mask" "F.Paste")
			(net "_NC_DDR0_32B_RAS_L")
		)
		(pad "J9" smd circle
			(at -7.50001 -7.50001 180)
			(size 0.508 0.508)
			(layers "F.Cu" "F.Mask" "F.Paste")
			(net "_NC_DDR0_32B_CS1_L")
		)
		(pad "J10" smd circle
			(at -6.500012 -7.50001 180)
			(size 0.508 0.508)
			(layers "F.Cu" "F.Mask" "F.Paste")
			(net "_NC_B_DZQ1")
		)
		(pad "J11" smd circle
			(at -5.499989 -7.50001 180)
			(size 0.508 0.508)
			(layers "F.Cu" "F.Mask" "F.Paste")
			(net "VDD_CORE")
		)
		(pad "J12" smd circle
			(at -4.499991 -7.50001 180)
			(size 0.508 0.508)
			(layers "F.Cu" "F.Mask" "F.Paste")
			(net "GND")
		)
		(pad "J13" smd circle
			(at -3.499993 -7.50001 180)
			(size 0.508 0.508)
			(layers "F.Cu" "F.Mask" "F.Paste")
			(net "VDD_CORE")
		)
		(pad "J14" smd circle
			(at -2.499995 -7.50001 180)
			(size 0.508 0.508)
			(layers "F.Cu" "F.Mask" "F.Paste")
			(net "GND")
		)
		(pad "J15" smd circle
			(at -1.499997 -7.50001 180)
			(size 0.508 0.508)
			(layers "F.Cu" "F.Mask" "F.Paste")
			(net "VDD_CORE")
		)
		(pad "J16" smd circle
			(at -0.499999 -7.50001 180)
			(size 0.508 0.508)
			(layers "F.Cu" "F.Mask" "F.Paste")
			(net "GND")
		)
		(pad "J17" smd circle
			(at 0.499999 -7.50001 180)
			(size 0.508 0.508)
			(layers "F.Cu" "F.Mask" "F.Paste")
			(net "VDD_CORE")
		)
		(pad "J18" smd circle
			(at 1.499997 -7.50001 180)
			(size 0.508 0.508)
			(layers "F.Cu" "F.Mask" "F.Paste")
			(net "GND")
		)
		(pad "J19" smd circle
			(at 2.499995 -7.50001 180)
			(size 0.508 0.508)
			(layers "F.Cu" "F.Mask" "F.Paste")
			(net "VDD_CORE")
		)
		(pad "J20" smd circle
			(at 3.499993 -7.50001 180)
			(size 0.508 0.508)
			(layers "F.Cu" "F.Mask" "F.Paste")
			(net "GND")
		)
		(pad "J21" smd circle
			(at 4.499991 -7.50001 180)
			(size 0.508 0.508)
			(layers "F.Cu" "F.Mask" "F.Paste")
			(net "VDD_CORE")
		)
		(pad "J22" smd circle
			(at 5.499989 -7.50001 180)
			(size 0.508 0.508)
			(layers "F.Cu" "F.Mask" "F.Paste")
			(net "GND")
		)
		(pad "J23" smd circle
			(at 6.500012 -7.50001 180)
			(size 0.508 0.508)
			(layers "F.Cu" "F.Mask" "F.Paste")
			(net "VDD_CORE")
		)
		(pad "J24" smd circle
			(at 7.50001 -7.50001 180)
			(size 0.508 0.508)
			(layers "F.Cu" "F.Mask" "F.Paste")
			(net "GND")
		)
		(pad "J25" smd circle
			(at 8.500008 -7.50001 180)
			(size 0.508 0.508)
			(layers "F.Cu" "F.Mask" "F.Paste")
			(net "VDD_CORE")
		)
		(pad "J26" smd circle
			(at 9.500006 -7.50001 180)
			(size 0.508 0.508)
			(layers "F.Cu" "F.Mask" "F.Paste")
			(net "GND")
		)
		(pad "J27" smd circle
			(at 10.500004 -7.50001 180)
			(size 0.508 0.508)
			(layers "F.Cu" "F.Mask" "F.Paste")
			(net "_NC_VDDQ_TEST_SCAN_0_OUT_3")
		)
		(pad "J28" smd circle
			(at 11.500002 -7.50001 180)
			(size 0.508 0.508)
			(layers "F.Cu" "F.Mask" "F.Paste")
			(net "_NC_TEST_SCAN_0_OUT4")
		)
		(pad "J29" smd circle
			(at 12.5 -7.50001 180)
			(size 0.508 0.508)
			(layers "F.Cu" "F.Mask" "F.Paste")
			(net "_NC_TEST_SCAN_0_OUT3")
		)
		(pad "J30" smd circle
			(at 13.499998 -7.50001 180)
			(size 0.508 0.508)
			(layers "F.Cu" "F.Mask" "F.Paste")
			(net "_NC_TEST_SCAN_0_OUT2")
		)
		(pad "J31" smd circle
			(at 14.499996 -7.50001 180)
			(size 0.508 0.508)
			(layers "F.Cu" "F.Mask" "F.Paste")
			(net "_NC_TEST_SCAN_0_OUT1")
		)
		(pad "J32" smd circle
			(at 15.499994 -7.50001 180)
			(size 0.508 0.508)
			(layers "F.Cu" "F.Mask" "F.Paste")
			(net "_NC_TEST_SCAN_0_OUT0")
		)
		(pad "K1" smd circle
			(at -15.499994 -6.500012 180)
			(size 0.508 0.508)
			(layers "F.Cu" "F.Mask" "F.Paste")
			(net "_NC_DDR0_32B_DQ21")
		)
		(pad "K2" smd circle
			(at -14.499996 -6.500012 180)
			(size 0.508 0.508)
			(layers "F.Cu" "F.Mask" "F.Paste")
			(net "_NC_DDR0_32B_DQ20")
		)
		(pad "K3" smd circle
			(at -13.499998 -6.500012 180)
			(size 0.508 0.508)
			(layers "F.Cu" "F.Mask" "F.Paste")
			(net "GND")
		)
		(pad "K4" smd circle
			(at -12.5 -6.500012 180)
			(size 0.508 0.508)
			(layers "F.Cu" "F.Mask" "F.Paste")
			(net "_NC_DDR0_32B_DQ14")
		)
		(pad "K5" smd circle
			(at -11.500002 -6.500012 180)
			(size 0.508 0.508)
			(layers "F.Cu" "F.Mask" "F.Paste")
			(net "_NC_DDR0_32B_DQ8")
		)
		(pad "K6" smd circle
			(at -10.500004 -6.500012 180)
			(size 0.508 0.508)
			(layers "F.Cu" "F.Mask" "F.Paste")
			(net "GND")
		)
		(pad "K7" smd circle
			(at -9.500006 -6.500012 180)
			(size 0.508 0.508)
			(layers "F.Cu" "F.Mask" "F.Paste")
			(net "_NC_DDR0_32B_A1")
		)
		(pad "K8" smd circle
			(at -8.500008 -6.500012 180)
			(size 0.508 0.508)
			(layers "F.Cu" "F.Mask" "F.Paste")
			(net "_NC_DDR0_32B_A6")
		)
		(pad "K9" smd circle
			(at -7.50001 -6.500012 180)
			(size 0.508 0.508)
			(layers "F.Cu" "F.Mask" "F.Paste")
			(net "_NC_DDR0_32B_CAS_L")
		)
		(pad "K10" smd circle
			(at -6.500012 -6.500012 180)
			(size 0.508 0.508)
			(layers "F.Cu" "F.Mask" "F.Paste")
			(net "A_DZQ1")
		)
		(pad "K11" smd circle
			(at -5.499989 -6.500012 180)
			(size 0.508 0.508)
			(layers "F.Cu" "F.Mask" "F.Paste")
			(net "GND")
		)
		(pad "K12" smd circle
			(at -4.499991 -6.500012 180)
			(size 0.508 0.508)
			(layers "F.Cu" "F.Mask" "F.Paste")
			(net "VDD_CORE")
		)
		(pad "K13" smd circle
			(at -3.499993 -6.500012 180)
			(size 0.508 0.508)
			(layers "F.Cu" "F.Mask" "F.Paste")
			(net "GND")
		)
		(pad "K14" smd circle
			(at -2.499995 -6.500012 180)
			(size 0.508 0.508)
			(layers "F.Cu" "F.Mask" "F.Paste")
			(net "VDD_CORE")
		)
		(pad "K15" smd circle
			(at -1.499997 -6.500012 180)
			(size 0.508 0.508)
			(layers "F.Cu" "F.Mask" "F.Paste")
			(net "GND")
		)
		(pad "K16" smd circle
			(at -0.499999 -6.500012 180)
			(size 0.508 0.508)
			(layers "F.Cu" "F.Mask" "F.Paste")
			(net "VDD_CORE")
		)
		(pad "K17" smd circle
			(at 0.499999 -6.500012 180)
			(size 0.508 0.508)
			(layers "F.Cu" "F.Mask" "F.Paste")
			(net "GND")
		)
		(pad "K18" smd circle
			(at 1.499997 -6.500012 180)
			(size 0.508 0.508)
			(layers "F.Cu" "F.Mask" "F.Paste")
			(net "VDD_CORE")
		)
		(pad "K19" smd circle
			(at 2.499995 -6.500012 180)
			(size 0.508 0.508)
			(layers "F.Cu" "F.Mask" "F.Paste")
			(net "GND")
		)
		(pad "K20" smd circle
			(at 3.499993 -6.500012 180)
			(size 0.508 0.508)
			(layers "F.Cu" "F.Mask" "F.Paste")
			(net "VDD_CORE")
		)
		(pad "K21" smd circle
			(at 4.499991 -6.500012 180)
			(size 0.508 0.508)
			(layers "F.Cu" "F.Mask" "F.Paste")
			(net "GND")
		)
		(pad "K22" smd circle
			(at 5.499989 -6.500012 180)
			(size 0.508 0.508)
			(layers "F.Cu" "F.Mask" "F.Paste")
			(net "VDD_CORE")
		)
		(pad "K23" smd circle
			(at 6.500012 -6.500012 180)
			(size 0.508 0.508)
			(layers "F.Cu" "F.Mask" "F.Paste")
			(net "GND")
		)
		(pad "K24" smd circle
			(at 7.50001 -6.500012 180)
			(size 0.508 0.508)
			(layers "F.Cu" "F.Mask" "F.Paste")
			(net "VDD_CORE")
		)
		(pad "K25" smd circle
			(at 8.500008 -6.500012 180)
			(size 0.508 0.508)
			(layers "F.Cu" "F.Mask" "F.Paste")
			(net "GND")
		)
	)
)
